# T6G (Grand Teton) — schematic netlist excerpt (pin names and nets, part order shuffled) for the footprints in the layout excerpt that follows; sources: Cadence DE-HDL packaged netlist, KiCad conversion of 04192023_DAF0TMB3IC0_F0TG_MB_C_brd_V02_OCP.brd

C611  Q_CAP  0.1UF 25V 10% X7R  pkg 0402  page 160 : A = P3V3_AUX ; B = GND
C336  Q_CAP  4.7UF 6.3V 20% X6S  pkg 0402  page 334 : A = P0V9_CPU1_RT1_2A ; B = GND

(kicad_pcb
	(version 20260206)
	(generator "pcbnew")
	(generator_version "10.0")
	(general
		(thickness 1.6)
		(legacy_teardrops no)
	)
	(paper "A4")
	(title_block
		(title "04192023_DAF0TMB3IC0_F0TG_MB_C_brd_V02_OCP.brd")
		(comment 1 "Grand Teton / footprints 8247-8248 of 8354")
	)
	(layers
		(0 "F.Cu" signal "TOP")
		(4 "In1.Cu" signal "GND")
		(6 "In2.Cu" signal "IN1")
		(8 "In3.Cu" signal "GND1")
		(10 "In4.Cu" signal "IN2")
		(12 "In5.Cu" signal "GND2")
		(14 "In6.Cu" signal "IN3")
		(16 "In7.Cu" signal "GND3")
		(18 "In8.Cu" signal "VCC")
		(20 "In9.Cu" signal "VCC1")
		(22 "In10.Cu" signal "GND4")
		(24 "In11.Cu" signal "IN4")
		(26 "In12.Cu" signal "GND5")
		(28 "In13.Cu" signal "IN5")
		(30 "In14.Cu" signal "GND6")
		(32 "In15.Cu" signal "IN6")
		(34 "In16.Cu" signal "GND7")
		(2 "B.Cu" signal "BOTTOM")
		(9 "F.Adhes" user "F.Adhesive")
		(11 "B.Adhes" user "B.Adhesive")
		(13 "F.Paste" user "Package Geometry/Pastemask Top")
		(15 "B.Paste" user "Package Geometry/Pastemask Bottom")
		(5 "F.SilkS" user "Ref Des/Silkscreen Top")
		(7 "B.SilkS" user "Ref Des/Silkscreen Bottom")
		(1 "F.Mask" user "Board Geometry/Soldermask Top")
		(3 "B.Mask" user "Board Geometry/Soldermask Bottom")
		(17 "Dwgs.User" user "User.Drawings")
		(19 "Cmts.User" user "User.Comments")
		(21 "Eco1.User" user "User.Eco1")
		(23 "Eco2.User" user "User.Eco2")
		(25 "Edge.Cuts" user "Board Geometry/Outline")
		(27 "Margin" user)
		(31 "F.CrtYd" user "Package Geometry/Place Bound Top")
		(29 "B.CrtYd" user "Package Geometry/Place Bound Bottom")
		(35 "F.Fab" user "Ref Des/Assembly Top")
		(33 "B.Fab" user "Ref Des/Assembly Bottom")
	)
	(footprint ""
		(layer "B.Cu")
		(at 241.173 -222.25 -90)
		(property "Reference" "C611"
			(at 0 0 90)
			(layer "B.SilkS")
			(hide yes)
			(effects
				(font
					(size 1.27 1.27)
				)
				(justify mirror)
			)
		)
		(property "Value" ""
			(at 0 0 90)
			(layer "B.Fab")
			(effects
				(font
					(size 1.27 1.27)
				)
				(justify mirror)
			)
		)
		(duplicate_pad_numbers_are_jumpers no)
		(fp_line
			(start -0.7874 0.4064)
			(end 0.7874 0.4064)
			(stroke
				(width 0.1524)
				(type default)
			)
			(layer "B.SilkS")
		)
		(fp_line
			(start 0.7874 0.4064)
			(end 0.7874 -0.4064)
			(stroke
				(width 0.1524)
				(type default)
			)
			(layer "B.SilkS")
		)
		(fp_line
			(start -0.7874 -0.4064)
			(end -0.7874 0.4064)
			(stroke
				(width 0.1524)
				(type default)
			)
			(layer "B.SilkS")
		)
		(fp_line
			(start 0.7874 -0.4064)
			(end -0.7874 -0.4064)
			(stroke
				(width 0.1524)
				(type default)
			)
			(layer "B.SilkS")
		)
		(fp_line
			(start -0.67945 0.3048)
			(end -0.120396 0.3048)
			(stroke
				(width 0.1)
				(type default)
			)
			(layer "B.Fab")
		)
		(fp_line
			(start -0.120396 0.3048)
			(end -0.120396 0.2794)
			(stroke
				(width 0.1)
				(type default)
			)
			(layer "B.Fab")
		)
		(fp_line
			(start 0.12065 0.3048)
			(end 0.67945 0.3048)
			(stroke
				(width 0.1)
				(type default)
			)
			(layer "B.Fab")
		)
		(fp_line
			(start 0.67945 0.3048)
			(end 0.67945 -0.305054)
			(stroke
				(width 0.1)
				(type default)
			)
			(layer "B.Fab")
		)
		(fp_line
			(start -0.120396 0.2794)
			(end 0.12065 0.2794)
			(stroke
				(width 0.1)
				(type default)
			)
			(layer "B.Fab")
		)
		(fp_line
			(start 0.12065 0.2794)
			(end 0.12065 0.3048)
			(stroke
				(width 0.1)
				(type default)
			)
			(layer "B.Fab")
		)
		(fp_line
			(start -0.12065 -0.2794)
			(end -0.12065 -0.3048)
			(stroke
				(width 0.1)
				(type default)
			)
			(layer "B.Fab")
		)
		(fp_line
			(start 0.12065 -0.2794)
			(end -0.12065 -0.2794)
			(stroke
				(width 0.1)
				(type default)
			)
			(layer "B.Fab")
		)
		(fp_line
			(start -0.67945 -0.3048)
			(end -0.67945 0.3048)
			(stroke
				(width 0.1)
				(type default)
			)
			(layer "B.Fab")
		)
		(fp_line
			(start -0.12065 -0.3048)
			(end -0.67945 -0.3048)
			(stroke
				(width 0.1)
				(type default)
			)
			(layer "B.Fab")
		)
		(fp_line
			(start 0.12065 -0.305054)
			(end 0.12065 -0.2794)
			(stroke
				(width 0.1)
				(type default)
			)
			(layer "B.Fab")
		)
		(fp_line
			(start 0.67945 -0.305054)
			(end 0.12065 -0.305054)
			(stroke
				(width 0.1)
				(type default)
			)
			(layer "B.Fab")
		)
		(pad "1" smd circle
			(at 0.40005 0 90)
			(size 0 0)
			(layers "B.Cu" "B.Mask" "B.Paste")
			(net "P3V3_AUX")
		)
		(pad "2" smd circle
			(at -0.40005 0 90)
			(size 0 0)
			(layers "B.Cu" "B.Mask" "B.Paste")
			(net "GND")
		)
	)
	(footprint ""
		(layer "B.Cu")
		(at 79.015082 -391.340848 -90)
		(property "Reference" "C336"
			(at 0 0 90)
			(layer "B.SilkS")
			(hide yes)
			(effects
				(font
					(size 1.27 1.27)
				)
				(justify mirror)
			)
		)
		(property "Value" ""
			(at 0 0 90)
			(layer "B.Fab")
			(effects
				(font
					(size 1.27 1.27)
				)
				(justify mirror)
			)
		)
		(duplicate_pad_numbers_are_jumpers no)
		(fp_line
			(start -0.7874 0.4064)
			(end 0.7874 0.4064)
			(stroke
				(width 0.1524)
				(type default)
			)
			(layer "B.SilkS")
		)
		(fp_line
			(start 0.7874 0.4064)
			(end 0.7874 -0.4064)
			(stroke
				(width 0.1524)
				(type default)
			)
			(layer "B.SilkS")
		)
		(fp_line
			(start -0.7874 -0.4064)
			(end -0.7874 0.4064)
			(stroke
				(width 0.1524)
				(type default)
			)
			(layer "B.SilkS")
		)
		(fp_line
			(start 0.7874 -0.4064)
			(end -0.7874 -0.4064)
			(stroke
				(width 0.1524)
				(type default)
			)
			(layer "B.SilkS")
		)
		(fp_line
			(start -0.67945 0.3048)
			(end -0.120396 0.3048)
			(stroke
				(width 0.1)
				(type default)
			)
			(layer "B.Fab")
		)
		(fp_line
			(start -0.120396 0.3048)
			(end -0.120396 0.2794)
			(stroke
				(width 0.1)
				(type default)
			)
			(layer "B.Fab")
		)
		(fp_line
			(start 0.12065 0.3048)
			(end 0.67945 0.3048)
			(stroke
				(width 0.1)
				(type default)
			)
			(layer "B.Fab")
		)
		(fp_line
			(start 0.67945 0.3048)
			(end 0.67945 -0.305054)
			(stroke
				(width 0.1)
				(type default)
			)
			(layer "B.Fab")
		)
		(fp_line
			(start -0.120396 0.2794)
			(end 0.12065 0.2794)
			(stroke
				(width 0.1)
				(type default)
			)
			(layer "B.Fab")
		)
		(fp_line
			(start 0.12065 0.2794)
			(end 0.12065 0.3048)
			(stroke
				(width 0.1)
				(type default)
			)
			(layer "B.Fab")
		)
		(fp_line
			(start -0.12065 -0.2794)
			(end -0.12065 -0.3048)
			(stroke
				(width 0.1)
				(type default)
			)
			(layer "B.Fab")
		)
		(fp_line
			(start 0.12065 -0.2794)
			(end -0.12065 -0.2794)
			(stroke
				(width 0.1)
				(type default)
			)
			(layer "B.Fab")
		)
		(fp_line
			(start -0.67945 -0.3048)
			(end -0.67945 0.3048)
			(stroke
				(width 0.1)
				(type default)
			)
			(layer "B.Fab")
		)
		(fp_line
			(start -0.12065 -0.3048)
			(end -0.67945 -0.3048)
			(stroke
				(width 0.1)
				(type default)
			)
			(layer "B.Fab")
		)
		(fp_line
			(start 0.12065 -0.305054)
			(end 0.12065 -0.2794)
			(stroke
				(width 0.1)
				(type default)
			)
			(layer "B.Fab")
		)
		(fp_line
			(start 0.67945 -0.305054)
			(end 0.12065 -0.305054)
			(stroke
				(width 0.1)
				(type default)
			)
			(layer "B.Fab")
		)
		(pad "1" smd circle
			(at 0.40005 0 90)
			(size 0 0)
			(layers "B.Cu" "B.Mask" "B.Paste")
			(net "P0V9_CPU1_RT1_2A")
		)
		(pad "2" smd circle
			(at -0.40005 0 90)
			(size 0 0)
			(layers "B.Cu" "B.Mask" "B.Paste")
			(net "GND")
		)
	)
)
